# T6G (Grand Teton) — schematic netlist excerpt (pin names and nets, part order shuffled) for the footprints in the layout excerpt that follows; sources: Cadence DE-HDL packaged netlist, KiCad conversion of 04192023_DAF0TMB3IC0_F0TG_MB_C_brd_V02_OCP.brd

PC2149  Q_CAP  0.01UF 50V 10% EMPTY  pkg C0402  page 140 : A = P3V3_OCP_V3_2_R ; B = P3V3_OCP_GATE_2
C504  Q_CAP  22UF 4V 20% X6S  pkg C0402  page 279 : A = P1V8_CPU0_RT_1D ; B = GND

(kicad_pcb
	(version 20260206)
	(generator "pcbnew")
	(generator_version "10.0")
	(general
		(thickness 1.6)
		(legacy_teardrops no)
	)
	(paper "A4")
	(title_block
		(title "04192023_DAF0TMB3IC0_F0TG_MB_C_brd_V02_OCP.brd")
		(comment 1 "Grand Teton / footprints 1138-1139 of 8354")
	)
	(layers
		(0 "F.Cu" signal "TOP")
		(4 "In1.Cu" signal "GND")
		(6 "In2.Cu" signal "IN1")
		(8 "In3.Cu" signal "GND1")
		(10 "In4.Cu" signal "IN2")
		(12 "In5.Cu" signal "GND2")
		(14 "In6.Cu" signal "IN3")
		(16 "In7.Cu" signal "GND3")
		(18 "In8.Cu" signal "VCC")
		(20 "In9.Cu" signal "VCC1")
		(22 "In10.Cu" signal "GND4")
		(24 "In11.Cu" signal "IN4")
		(26 "In12.Cu" signal "GND5")
		(28 "In13.Cu" signal "IN5")
		(30 "In14.Cu" signal "GND6")
		(32 "In15.Cu" signal "IN6")
		(34 "In16.Cu" signal "GND7")
		(2 "B.Cu" signal "BOTTOM")
		(9 "F.Adhes" user "F.Adhesive")
		(11 "B.Adhes" user "B.Adhesive")
		(13 "F.Paste" user "Package Geometry/Pastemask Top")
		(15 "B.Paste" user "Package Geometry/Pastemask Bottom")
		(5 "F.SilkS" user "Ref Des/Silkscreen Top")
		(7 "B.SilkS" user "Ref Des/Silkscreen Bottom")
		(1 "F.Mask" user "Board Geometry/Soldermask Top")
		(3 "B.Mask" user "Board Geometry/Soldermask Bottom")
		(17 "Dwgs.User" user "User.Drawings")
		(19 "Cmts.User" user "User.Comments")
		(21 "Eco1.User" user "User.Eco1")
		(23 "Eco2.User" user "User.Eco2")
		(25 "Edge.Cuts" user "Board Geometry/Outline")
		(27 "Margin" user)
		(31 "F.CrtYd" user "Package Geometry/Place Bound Top")
		(29 "B.CrtYd" user "Package Geometry/Place Bound Bottom")
		(35 "F.Fab" user "Ref Des/Assembly Top")
		(33 "B.Fab" user "Ref Des/Assembly Bottom")
	)
	(footprint ""
		(layer "F.Cu")
		(at 326.992488 -394.82268 90)
		(property "Reference" "C504"
			(at 0 0 90)
			(layer "F.SilkS")
			(hide yes)
			(effects
				(font
					(size 1.27 1.27)
				)
			)
		)
		(property "Value" ""
			(at 0 0 90)
			(layer "F.Fab")
			(effects
				(font
					(size 1.27 1.27)
				)
			)
		)
		(duplicate_pad_numbers_are_jumpers no)
		(fp_line
			(start 0.7874 -0.4064)
			(end 0.7874 0.4064)
			(stroke
				(width 0.1524)
				(type default)
			)
			(layer "F.SilkS")
		)
		(fp_line
			(start -0.7874 -0.4064)
			(end 0.7874 -0.4064)
			(stroke
				(width 0.1524)
				(type default)
			)
			(layer "F.SilkS")
		)
		(fp_line
			(start 0.7874 0.4064)
			(end -0.7874 0.4064)
			(stroke
				(width 0.1524)
				(type default)
			)
			(layer "F.SilkS")
		)
		(fp_line
			(start -0.7874 0.4064)
			(end -0.7874 -0.4064)
			(stroke
				(width 0.1524)
				(type default)
			)
			(layer "F.SilkS")
		)
		(fp_line
			(start -0.12065 -0.305054)
			(end -0.12065 -0.2794)
			(stroke
				(width 0.1)
				(type default)
			)
			(layer "F.Fab")
		)
		(fp_line
			(start -0.67945 -0.305054)
			(end -0.12065 -0.305054)
			(stroke
				(width 0.1)
				(type default)
			)
			(layer "F.Fab")
		)
		(fp_line
			(start 0.67945 -0.3048)
			(end 0.67945 0.3048)
			(stroke
				(width 0.1)
				(type default)
			)
			(layer "F.Fab")
		)
		(fp_line
			(start 0.12065 -0.3048)
			(end 0.67945 -0.3048)
			(stroke
				(width 0.1)
				(type default)
			)
			(layer "F.Fab")
		)
		(fp_line
			(start 0.12065 -0.2794)
			(end 0.12065 -0.3048)
			(stroke
				(width 0.1)
				(type default)
			)
			(layer "F.Fab")
		)
		(fp_line
			(start -0.12065 -0.2794)
			(end 0.12065 -0.2794)
			(stroke
				(width 0.1)
				(type default)
			)
			(layer "F.Fab")
		)
		(fp_line
			(start 0.120396 0.2794)
			(end -0.12065 0.2794)
			(stroke
				(width 0.1)
				(type default)
			)
			(layer "F.Fab")
		)
		(fp_line
			(start -0.12065 0.2794)
			(end -0.12065 0.3048)
			(stroke
				(width 0.1)
				(type default)
			)
			(layer "F.Fab")
		)
		(fp_line
			(start 0.67945 0.3048)
			(end 0.120396 0.3048)
			(stroke
				(width 0.1)
				(type default)
			)
			(layer "F.Fab")
		)
		(fp_line
			(start 0.120396 0.3048)
			(end 0.120396 0.2794)
			(stroke
				(width 0.1)
				(type default)
			)
			(layer "F.Fab")
		)
		(fp_line
			(start -0.12065 0.3048)
			(end -0.67945 0.3048)
			(stroke
				(width 0.1)
				(type default)
			)
			(layer "F.Fab")
		)
		(fp_line
			(start -0.67945 0.3048)
			(end -0.67945 -0.305054)
			(stroke
				(width 0.1)
				(type default)
			)
			(layer "F.Fab")
		)
		(pad "1" smd circle
			(at -0.40005 0 90)
			(size 0 0)
			(layers "F.Cu" "F.Mask" "F.Paste")
			(net "P1V8_CPU0_RT_1D")
		)
		(pad "2" smd circle
			(at 0.40005 0 90)
			(size 0 0)
			(layers "F.Cu" "F.Mask" "F.Paste")
			(net "GND")
		)
	)
	(footprint ""
		(layer "F.Cu")
		(at 89.89441 -54.69255)
		(property "Reference" "PC2149"
			(at 0 0 0)
			(layer "F.SilkS")
			(hide yes)
			(effects
				(font
					(size 1.27 1.27)
				)
			)
		)
		(property "Value" ""
			(at 0 0 0)
			(layer "F.Fab")
			(effects
				(font
					(size 1.27 1.27)
				)
			)
		)
		(duplicate_pad_numbers_are_jumpers no)
		(fp_line
			(start -0.7874 -0.4064)
			(end 0.7874 -0.4064)
			(stroke
				(width 0.1524)
				(type default)
			)
			(layer "F.SilkS")
		)
		(fp_line
			(start -0.7874 0.4064)
			(end -0.7874 -0.4064)
			(stroke
				(width 0.1524)
				(type default)
			)
			(layer "F.SilkS")
		)
		(fp_line
			(start 0.7874 -0.4064)
			(end 0.7874 0.4064)
			(stroke
				(width 0.1524)
				(type default)
			)
			(layer "F.SilkS")
		)
		(fp_line
			(start 0.7874 0.4064)
			(end -0.7874 0.4064)
			(stroke
				(width 0.1524)
				(type default)
			)
			(layer "F.SilkS")
		)
		(fp_line
			(start -0.67945 -0.305054)
			(end -0.12065 -0.305054)
			(stroke
				(width 0.1)
				(type default)
			)
			(layer "F.Fab")
		)
		(fp_line
			(start -0.67945 0.3048)
			(end -0.67945 -0.305054)
			(stroke
				(width 0.1)
				(type default)
			)
			(layer "F.Fab")
		)
		(fp_line
			(start -0.12065 -0.305054)
			(end -0.12065 -0.2794)
			(stroke
				(width 0.1)
				(type default)
			)
			(layer "F.Fab")
		)
		(fp_line
			(start -0.12065 -0.2794)
			(end 0.12065 -0.2794)
			(stroke
				(width 0.1)
				(type default)
			)
			(layer "F.Fab")
		)
		(fp_line
			(start -0.12065 0.2794)
			(end -0.12065 0.3048)
			(stroke
				(width 0.1)
				(type default)
			)
			(layer "F.Fab")
		)
		(fp_line
			(start -0.12065 0.3048)
			(end -0.67945 0.3048)
			(stroke
				(width 0.1)
				(type default)
			)
			(layer "F.Fab")
		)
		(fp_line
			(start 0.120396 0.2794)
			(end -0.12065 0.2794)
			(stroke
				(width 0.1)
				(type default)
			)
			(layer "F.Fab")
		)
		(fp_line
			(start 0.120396 0.3048)
			(end 0.120396 0.2794)
			(stroke
				(width 0.1)
				(type default)
			)
			(layer "F.Fab")
		)
		(fp_line
			(start 0.12065 -0.3048)
			(end 0.67945 -0.3048)
			(stroke
				(width 0.1)
				(type default)
			)
			(layer "F.Fab")
		)
		(fp_line
			(start 0.12065 -0.2794)
			(end 0.12065 -0.3048)
			(stroke
				(width 0.1)
				(type default)
			)
			(layer "F.Fab")
		)
		(fp_line
			(start 0.67945 -0.3048)
			(end 0.67945 0.3048)
			(stroke
				(width 0.1)
				(type default)
			)
			(layer "F.Fab")
		)
		(fp_line
			(start 0.67945 0.3048)
			(end 0.120396 0.3048)
			(stroke
				(width 0.1)
				(type default)
			)
			(layer "F.Fab")
		)
		(pad "1" smd circle
			(at -0.40005 0)
			(size 0 0)
			(layers "F.Cu" "F.Mask" "F.Paste")
			(net "P3V3_OCP_V3_2_R")
		)
		(pad "2" smd circle
			(at 0.40005 0)
			(size 0 0)
			(layers "F.Cu" "F.Mask" "F.Paste")
			(net "P3V3_OCP_GATE_2")
		)
	)
)
